(kicad_pcb
	(version 20241229)
	(generator "pcbnew")
	(generator_version "9.0")
	(general
		(thickness 1.294)
		(legacy_teardrops no)
	)
	(paper "A3")
	(title_block
		(title "Kintex 410T devboard")
		(date "2024-04-03")
		(rev "1.1.2")
		(comment 9 "footprints 673-678 of 975")
	)
	(layers
		(0 "F.Cu" mixed)
		(4 "In1.Cu" power)
		(6 "In2.Cu" power)
		(8 "In3.Cu" mixed)
		(10 "In4.Cu" power)
		(12 "In5.Cu" mixed)
		(14 "In6.Cu" power)
		(16 "In7.Cu" mixed)
		(18 "In8.Cu" power)
		(2 "B.Cu" mixed)
		(9 "F.Adhes" user "F.Adhesive")
		(11 "B.Adhes" user "B.Adhesive")
		(13 "F.Paste" user)
		(15 "B.Paste" user)
		(5 "F.SilkS" user "F.Silkscreen")
		(7 "B.SilkS" user "B.Silkscreen")
		(1 "F.Mask" user)
		(3 "B.Mask" user)
		(17 "Dwgs.User" user "User.Drawings")
		(19 "Cmts.User" user "User.Comments")
		(21 "Eco1.User" user "User.Eco1")
		(23 "Eco2.User" user "User.Eco2")
		(25 "Edge.Cuts" user)
		(27 "Margin" user)
		(31 "F.CrtYd" user "F.Courtyard")
		(29 "B.CrtYd" user "B.Courtyard")
		(35 "F.Fab" user)
		(33 "B.Fab" user)
	)
	(footprint "antmicro-footprints:C_0201"
		(layer "B.Cu")
		(at 184.350001 131.500001)
		(descr "Capacitor SMD 0201")
		(tags "capacitor SMD 0201")
		(property "Reference" "C160"
			(at -3.375001 0.374999 0)
			(layer "B.SilkS")
			(effects
				(font
					(size 0.7 0.7)
					(thickness 0.15)
				)
				(justify right bottom mirror)
			)
		)
		(property "Value" "C_4u7_0201"
			(at 0 -1.4 0)
			(layer "B.Fab")
			(effects
				(font
					(size 0.7 0.7)
					(thickness 0.15)
				)
				(justify right bottom mirror)
			)
		)
		(property "Description" "SMD Multilayer Ceramic Capacitor, 4.7 µF, 6.3 V, 0201 [0603 Metric], ± 20%, X5R, GRM Series"
			(at 0 0 0)
			(layer "F.Fab")
			(hide yes)
			(effects
				(font
					(size 1.27 1.27)
					(thickness 0.15)
				)
			)
		)
		(property "Author" "Antmicro"
			(at 0 0 0)
			(layer "B.Fab")
			(hide yes)
			(effects
				(font
					(size 1 1)
					(thickness 0.15)
				)
				(justify mirror)
			)
		)
		(property "Dielectric" ""
			(at 0 0 0)
			(layer "B.Fab")
			(hide yes)
			(effects
				(font
					(size 1 1)
					(thickness 0.15)
				)
				(justify mirror)
			)
		)
		(property "License" "Apache-2.0"
			(at 0 0 0)
			(layer "B.Fab")
			(hide yes)
			(effects
				(font
					(size 1 1)
					(thickness 0.15)
				)
				(justify mirror)
			)
		)
		(property "MPN" "GRM035R60J475ME15D"
			(at 0 0 0)
			(layer "B.Fab")
			(hide yes)
			(effects
				(font
					(size 1 1)
					(thickness 0.15)
				)
				(justify mirror)
			)
		)
		(property "Manufacturer" "Murata"
			(at 0 0 0)
			(layer "B.Fab")
			(hide yes)
			(effects
				(font
					(size 1 1)
					(thickness 0.15)
				)
				(justify mirror)
			)
		)
		(property "Val" "4u7"
			(at 0 0 0)
			(layer "B.Fab")
			(hide yes)
			(effects
				(font
					(size 1 1)
					(thickness 0.15)
				)
				(justify mirror)
			)
		)
		(property "Voltage" ""
			(at 0 0 0)
			(layer "B.Fab")
			(hide yes)
			(effects
				(font
					(size 1 1)
					(thickness 0.15)
				)
				(justify mirror)
			)
		)
		(sheetname "FPGA supply")
		(sheetfile "fpga-supply.kicad_sch")
		(attr smd)
		(fp_rect
			(start -0.7 0.35)
			(end 0.7 -0.35)
			(stroke
				(width 0.05)
				(type default)
			)
			(fill no)
			(layer "B.CrtYd")
		)
		(fp_rect
			(start 0.3 -0.15)
			(end -0.301 0.149)
			(stroke
				(width 0.15)
				(type solid)
			)
			(fill no)
			(layer "B.Fab")
		)
		(pad "" smd roundrect
			(at -0.349 0.002)
			(size 0.318 0.36)
			(layers "B.Paste")
			(roundrect_rratio 0.25)
		)
		(pad "" smd roundrect
			(at 0.341 0.002)
			(size 0.318 0.36)
			(layers "B.Paste")
			(roundrect_rratio 0.25)
		)
		(pad "1" smd roundrect
			(at -0.321 0.002)
			(size 0.46 0.4)
			(layers "B.Cu" "B.Mask")
			(roundrect_rratio 0.25)
			(net 1 "GND")
			(pintype "passive")
		)
		(pad "2" smd roundrect
			(at 0.32 0.002)
			(size 0.46 0.4)
			(layers "B.Cu" "B.Mask")
			(roundrect_rratio 0.25)
			(net 8 "+1V2_MGTAVTT")
			(pintype "passive")
		)
	)
	(footprint "antmicro-footprints:C_0402_1005Metric"
		(layer "B.Cu")
		(at 198 143.5)
		(descr "Capacitor SMD 0402")
		(tags "capacitor SMD 0402")
		(property "Reference" "C94"
			(at 1.1 1.225 180)
			(layer "B.SilkS")
			(effects
				(font
					(size 0.7 0.7)
					(thickness 0.15)
				)
				(justify left bottom mirror)
			)
		)
		(property "Value" "C_100n_0402"
			(at 0 -1.169 180)
			(layer "B.Fab")
			(effects
				(font
					(size 0.7 0.7)
					(thickness 0.15)
				)
				(justify left bottom mirror)
			)
		)
		(property "Description" "SMD Multilayer Ceramic Capacitor, 0.1 µF, 50 V, 0402 [1005 Metric], ± 10%, X5R, GRM Series"
			(at 0 0 0)
			(layer "F.Fab")
			(hide yes)
			(effects
				(font
					(size 1.27 1.27)
					(thickness 0.15)
				)
			)
		)
		(property "Author" "Antmicro"
			(at 0 0 0)
			(layer "B.Fab")
			(hide yes)
			(effects
				(font
					(size 1 1)
					(thickness 0.15)
				)
				(justify mirror)
			)
		)
		(property "Dielectric" "X5R"
			(at 0 0 0)
			(layer "B.Fab")
			(hide yes)
			(effects
				(font
					(size 1 1)
					(thickness 0.15)
				)
				(justify mirror)
			)
		)
		(property "License" "Apache-2.0"
			(at 0 0 0)
			(layer "B.Fab")
			(hide yes)
			(effects
				(font
					(size 1 1)
					(thickness 0.15)
				)
				(justify mirror)
			)
		)
		(property "MPN" "GRM155R61H104KE14D"
			(at 0 0 0)
			(layer "B.Fab")
			(hide yes)
			(effects
				(font
					(size 1 1)
					(thickness 0.15)
				)
				(justify mirror)
			)
		)
		(property "Manufacturer" "Murata"
			(at 0 0 0)
			(layer "B.Fab")
			(hide yes)
			(effects
				(font
					(size 1 1)
					(thickness 0.15)
				)
				(justify mirror)
			)
		)
		(property "Val" "100n"
			(at 0 0 0)
			(layer "B.Fab")
			(hide yes)
			(effects
				(font
					(size 1 1)
					(thickness 0.15)
				)
				(justify mirror)
			)
		)
		(property "Voltage" "50V"
			(at 0 0 0)
			(layer "B.Fab")
			(hide yes)
			(effects
				(font
					(size 1 1)
					(thickness 0.15)
				)
				(justify mirror)
			)
		)
		(sheetname "FPGA Bank 18 & 32")
		(sheetfile "fpga-bank-18-32.kicad_sch")
		(attr smd)
		(fp_rect
			(start -0.925 0.47)
			(end 0.925 -0.47)
			(stroke
				(width 0.05)
				(type default)
			)
			(fill no)
			(layer "B.CrtYd")
		)
		(fp_line
			(start -0.494 -0.248)
			(end -0.494 0.25)
			(stroke
				(width 0.15)
				(type solid)
			)
			(layer "B.Fab")
		)
		(fp_line
			(start -0.494 0.25)
			(end 0.504 0.25)
			(stroke
				(width 0.15)
				(type solid)
			)
			(layer "B.Fab")
		)
		(fp_line
			(start 0.504 -0.248)
			(end -0.494 -0.248)
			(stroke
				(width 0.15)
				(type solid)
			)
			(layer "B.Fab")
		)
		(fp_line
			(start 0.504 0.25)
			(end 0.504 -0.248)
			(stroke
				(width 0.15)
				(type solid)
			)
			(layer "B.Fab")
		)
		(pad "1" smd roundrect
			(at -0.48 0)
			(size 0.59 0.64)
			(layers "B.Cu" "B.Mask" "B.Paste")
			(roundrect_rratio 0.25)
			(net 1 "GND")
			(pintype "passive")
		)
		(pad "2" smd roundrect
			(at 0.48 0)
			(size 0.59 0.64)
			(layers "B.Cu" "B.Mask" "B.Paste")
			(roundrect_rratio 0.25)
			(net 26 "+1V8")
			(pintype "passive")
		)
	)
	(footprint "antmicro-footprints:R_0402_1005Metric"
		(layer "B.Cu")
		(at 237.599999 84.699999 -90)
		(descr "Resistor SMD 0402")
		(tags "resistor SMD 0402")
		(property "Reference" "R116"
			(at 0.750001 -0.425001 90)
			(layer "B.SilkS")
			(effects
				(font
					(size 0.7 0.7)
					(thickness 0.15)
				)
				(justify left bottom mirror)
			)
		)
		(property "Value" "R_100R_0402"
			(at 0 -1.4 90)
			(layer "B.Fab")
			(effects
				(font
					(size 0.7 0.7)
					(thickness 0.15)
				)
				(justify left bottom mirror)
			)
		)
		(property "Description" "SMD Chip Resistor, 100 ohm, ± 1%, 62.5 mW, 0402 [1005 Metric], Thick Film, General Purpose"
			(at 0 0 270)
			(layer "F.Fab")
			(hide yes)
			(effects
				(font
					(size 1.27 1.27)
					(thickness 0.15)
				)
			)
		)
		(property "Author" "Antmicro"
			(at 152.9 322.299998 0)
			(layer "B.Fab")
			(hide yes)
			(effects
				(font
					(size 1 1)
					(thickness 0.15)
				)
				(justify mirror)
			)
		)
		(property "License" "Apache-2.0"
			(at 152.9 322.299998 0)
			(layer "B.Fab")
			(hide yes)
			(effects
				(font
					(size 1 1)
					(thickness 0.15)
				)
				(justify mirror)
			)
		)
		(property "MPN" "CR0402-FX-1000GLF"
			(at 152.9 322.299998 0)
			(layer "B.Fab")
			(hide yes)
			(effects
				(font
					(size 1 1)
					(thickness 0.15)
				)
				(justify mirror)
			)
		)
		(property "Manufacturer" "Bourns"
			(at 152.9 322.299998 0)
			(layer "B.Fab")
			(hide yes)
			(effects
				(font
					(size 1 1)
					(thickness 0.15)
				)
				(justify mirror)
			)
		)
		(property "Tolerance" "1%"
			(at 152.9 322.299998 0)
			(layer "B.Fab")
			(hide yes)
			(effects
				(font
					(size 1 1)
					(thickness 0.15)
				)
				(justify mirror)
			)
		)
		(property "Val" "100R"
			(at 152.9 322.299998 0)
			(layer "B.Fab")
			(hide yes)
			(effects
				(font
					(size 1 1)
					(thickness 0.15)
				)
				(justify mirror)
			)
		)
		(sheetname "User GPIO + LED + button + DIP switch")
		(sheetfile "user-gpio.kicad_sch")
		(attr smd)
		(fp_rect
			(start -0.925 0.47)
			(end 0.925 -0.47)
			(stroke
				(width 0.05)
				(type default)
			)
			(fill no)
			(layer "B.CrtYd")
		)
		(fp_rect
			(start -0.5 0.25)
			(end 0.5 -0.25)
			(stroke
				(width 0.15)
				(type solid)
			)
			(fill no)
			(layer "B.Fab")
		)
		(pad "1" smd roundrect
			(at -0.48 0 270)
			(size 0.59 0.64)
			(layers "B.Cu" "B.Mask" "B.Paste")
			(roundrect_rratio 0.25)
			(net 816 "/User GPIO + LED + button + DIP switch/PMOD_B_7")
			(pintype "passive")
		)
		(pad "2" smd roundrect
			(at 0.48 0 270)
			(size 0.59 0.64)
			(layers "B.Cu" "B.Mask" "B.Paste")
			(roundrect_rratio 0.25)
			(net 442 "/FPGA Bank 12 & 13/PMOD_B.IO7")
			(pintype "passive")
		)
	)
	(footprint "antmicro-footprints:C_0402_1005Metric"
		(layer "B.Cu")
		(at 260.301 123 90)
		(descr "Capacitor SMD 0402")
		(tags "capacitor SMD 0402")
		(property "Reference" "C402"
			(at 1.45 1.274 270)
			(layer "B.SilkS")
			(effects
				(font
					(size 0.7 0.7)
					(thickness 0.15)
				)
				(justify left bottom mirror)
			)
		)
		(property "Value" "C_100n_0402"
			(at 0 -1.169 270)
			(layer "B.Fab")
			(effects
				(font
					(size 0.7 0.7)
					(thickness 0.15)
				)
				(justify left bottom mirror)
			)
		)
		(property "Description" "SMD Multilayer Ceramic Capacitor, 0.1 µF, 50 V, 0402 [1005 Metric], ± 10%, X5R, GRM Series"
			(at 0 0 90)
			(layer "F.Fab")
			(hide yes)
			(effects
				(font
					(size 1.27 1.27)
					(thickness 0.15)
				)
			)
		)
		(property "Author" "Antmicro"
			(at 383.301 -137.301 0)
			(layer "B.Fab")
			(hide yes)
			(effects
				(font
					(size 1 1)
					(thickness 0.15)
				)
				(justify mirror)
			)
		)
		(property "Dielectric" "X5R"
			(at 383.301 -137.301 0)
			(layer "B.Fab")
			(hide yes)
			(effects
				(font
					(size 1 1)
					(thickness 0.15)
				)
				(justify mirror)
			)
		)
		(property "License" "Apache-2.0"
			(at 383.301 -137.301 0)
			(layer "B.Fab")
			(hide yes)
			(effects
				(font
					(size 1 1)
					(thickness 0.15)
				)
				(justify mirror)
			)
		)
		(property "MPN" "GRM155R61H104KE14D"
			(at 383.301 -137.301 0)
			(layer "B.Fab")
			(hide yes)
			(effects
				(font
					(size 1 1)
					(thickness 0.15)
				)
				(justify mirror)
			)
		)
		(property "Manufacturer" "Murata"
			(at 383.301 -137.301 0)
			(layer "B.Fab")
			(hide yes)
			(effects
				(font
					(size 1 1)
					(thickness 0.15)
				)
				(justify mirror)
			)
		)
		(property "Val" "100n"
			(at 383.301 -137.301 0)
			(layer "B.Fab")
			(hide yes)
			(effects
				(font
					(size 1 1)
					(thickness 0.15)
				)
				(justify mirror)
			)
		)
		(property "Voltage" "50V"
			(at 383.301 -137.301 0)
			(layer "B.Fab")
			(hide yes)
			(effects
				(font
					(size 1 1)
					(thickness 0.15)
				)
				(justify mirror)
			)
		)
		(sheetname "USB PHY")
		(sheetfile "usb-phy.kicad_sch")
		(attr smd)
		(fp_rect
			(start -0.925 0.47)
			(end 0.925 -0.47)
			(stroke
				(width 0.05)
				(type default)
			)
			(fill no)
			(layer "B.CrtYd")
		)
		(fp_line
			(start 0.504 -0.248)
			(end -0.494 -0.248)
			(stroke
				(width 0.15)
				(type solid)
			)
			(layer "B.Fab")
		)
		(fp_line
			(start -0.494 -0.248)
			(end -0.494 0.25)
			(stroke
				(width 0.15)
				(type solid)
			)
			(layer "B.Fab")
		)
		(fp_line
			(start 0.504 0.25)
			(end 0.504 -0.248)
			(stroke
				(width 0.15)
				(type solid)
			)
			(layer "B.Fab")
		)
		(fp_line
			(start -0.494 0.25)
			(end 0.504 0.25)
			(stroke
				(width 0.15)
				(type solid)
			)
			(layer "B.Fab")
		)
		(pad "1" smd roundrect
			(at -0.48 0 90)
			(size 0.59 0.64)
			(layers "B.Cu" "B.Mask" "B.Paste")
			(roundrect_rratio 0.25)
			(net 1 "GND")
			(pintype "passive")
		)
		(pad "2" smd roundrect
			(at 0.48 0 90)
			(size 0.59 0.64)
			(layers "B.Cu" "B.Mask" "B.Paste")
			(roundrect_rratio 0.25)
			(net 24 "+3V3")
			(pintype "passive")
		)
	)
	(footprint "antmicro-footprints:C_0402_1005Metric"
		(layer "B.Cu")
		(at 167.145001 83.635001 180)
		(descr "Capacitor SMD 0402")
		(tags "capacitor SMD 0402")
		(property "Reference" "C299"
			(at 0.820001 -0.389999 0)
			(layer "B.SilkS")
			(effects
				(font
					(size 0.7 0.7)
					(thickness 0.15)
				)
				(justify left bottom mirror)
			)
		)
		(property "Value" "C_100n_0402"
			(at 0 -1.4 0)
			(layer "B.Fab")
			(effects
				(font
					(size 0.7 0.7)
					(thickness 0.15)
				)
				(justify left bottom mirror)
			)
		)
		(property "Description" "SMD Multilayer Ceramic Capacitor, 0.1 µF, 50 V, 0402 [1005 Metric], ± 10%, X5R, GRM Series"
			(at 0 0 180)
			(layer "F.Fab")
			(hide yes)
			(effects
				(font
					(size 1.27 1.27)
					(thickness 0.15)
				)
			)
		)
		(property "Author" "Antmicro"
			(at 334.290002 167.270002 0)
			(layer "B.Fab")
			(hide yes)
			(effects
				(font
					(size 1 1)
					(thickness 0.15)
				)
				(justify mirror)
			)
		)
		(property "Dielectric" "X5R"
			(at 334.290002 167.270002 0)
			(layer "B.Fab")
			(hide yes)
			(effects
				(font
					(size 1 1)
					(thickness 0.15)
				)
				(justify mirror)
			)
		)
		(property "License" "Apache-2.0"
			(at 334.290002 167.270002 0)
			(layer "B.Fab")
			(hide yes)
			(effects
				(font
					(size 1 1)
					(thickness 0.15)
				)
				(justify mirror)
			)
		)
		(property "MPN" "GRM155R61H104KE14D"
			(at 334.290002 167.270002 0)
			(layer "B.Fab")
			(hide yes)
			(effects
				(font
					(size 1 1)
					(thickness 0.15)
				)
				(justify mirror)
			)
		)
		(property "Manufacturer" "Murata"
			(at 334.290002 167.270002 0)
			(layer "B.Fab")
			(hide yes)
			(effects
				(font
					(size 1 1)
					(thickness 0.15)
				)
				(justify mirror)
			)
		)
		(property "Val" "100n"
			(at 334.290002 167.270002 0)
			(layer "B.Fab")
			(hide yes)
			(effects
				(font
					(size 1 1)
					(thickness 0.15)
				)
				(justify mirror)
			)
		)
		(property "Voltage" "50V"
			(at 334.290002 167.270002 0)
			(layer "B.Fab")
			(hide yes)
			(effects
				(font
					(size 1 1)
					(thickness 0.15)
				)
				(justify mirror)
			)
		)
		(sheetname "FMC+ HSPC")
		(sheetfile "fmc-hspc.kicad_sch")
		(attr smd)
		(fp_rect
			(start -0.925 0.47)
			(end 0.925 -0.47)
			(stroke
				(width 0.05)
				(type default)
			)
			(fill no)
			(layer "B.CrtYd")
		)
		(fp_line
			(start 0.504 0.25)
			(end 0.504 -0.248)
			(stroke
				(width 0.15)
				(type solid)
			)
			(layer "B.Fab")
		)
		(fp_line
			(start 0.504 -0.248)
			(end -0.494 -0.248)
			(stroke
				(width 0.15)
				(type solid)
			)
			(layer "B.Fab")
		)
		(fp_line
			(start -0.494 0.25)
			(end 0.504 0.25)
			(stroke
				(width 0.15)
				(type solid)
			)
			(layer "B.Fab")
		)
		(fp_line
			(start -0.494 -0.248)
			(end -0.494 0.25)
			(stroke
				(width 0.15)
				(type solid)
			)
			(layer "B.Fab")
		)
		(pad "1" smd roundrect
			(at -0.48 0 180)
			(size 0.59 0.64)
			(layers "B.Cu" "B.Mask" "B.Paste")
			(roundrect_rratio 0.25)
			(net 63 "/FMC+ HSPC/GTX116.TX3_N")
			(pintype "passive")
		)
		(pad "2" smd roundrect
			(at 0.48 0 180)
			(size 0.59 0.64)
			(layers "B.Cu" "B.Mask" "B.Paste")
			(roundrect_rratio 0.25)
			(net 62 "/FMC+ HSPC/GTX_TX0_C_N")
			(pintype "passive")
		)
	)
	(footprint "antmicro-footprints:C_0402_1005Metric"
		(layer "B.Cu")
		(at 194.9 126.325 90)
		(descr "Capacitor SMD 0402")
		(tags "capacitor SMD 0402")
		(property "Reference" "C113"
			(at 31.2 23.4 270)
			(layer "B.SilkS")
			(effects
				(font
					(size 0.7 0.7)
					(thickness 0.15)
				)
				(justify left bottom mirror)
			)
		)
		(property "Value" "C_100n_0402"
			(at 0 -1.169 270)
			(layer "B.Fab")
			(effects
				(font
					(size 0.7 0.7)
					(thickness 0.15)
				)
				(justify left bottom mirror)
			)
		)
		(property "Description" "SMD Multilayer Ceramic Capacitor, 0.1 µF, 50 V, 0402 [1005 Metric], ± 10%, X5R, GRM Series"
			(at 0 0 90)
			(layer "F.Fab")
			(hide yes)
			(effects
				(font
					(size 1.27 1.27)
					(thickness 0.15)
				)
			)
		)
		(property "Author" "Antmicro"
			(at 321.225 -68.575 0)
			(layer "B.Fab")
			(hide yes)
			(effects
				(font
					(size 1 1)
					(thickness 0.15)
				)
				(justify mirror)
			)
		)
		(property "Dielectric" "X5R"
			(at 321.225 -68.575 0)
			(layer "B.Fab")
			(hide yes)
			(effects
				(font
					(size 1 1)
					(thickness 0.15)
				)
				(justify mirror)
			)
		)
		(property "License" "Apache-2.0"
			(at 321.225 -68.575 0)
			(layer "B.Fab")
			(hide yes)
			(effects
				(font
					(size 1 1)
					(thickness 0.15)
				)
				(justify mirror)
			)
		)
		(property "MPN" "GRM155R61H104KE14D"
			(at 321.225 -68.575 0)
			(layer "B.Fab")
			(hide yes)
			(effects
				(font
					(size 1 1)
					(thickness 0.15)
				)
				(justify mirror)
			)
		)
		(property "Manufacturer" "Murata"
			(at 321.225 -68.575 0)
			(layer "B.Fab")
			(hide yes)
			(effects
				(font
					(size 1 1)
					(thickness 0.15)
				)
				(justify mirror)
			)
		)
		(property "Val" "100n"
			(at 321.225 -68.575 0)
			(layer "B.Fab")
			(hide yes)
			(effects
				(font
					(size 1 1)
					(thickness 0.15)
				)
				(justify mirror)
			)
		)
		(property "Voltage" "50V"
			(at 321.225 -68.575 0)
			(layer "B.Fab")
			(hide yes)
			(effects
				(font
					(size 1 1)
					(thickness 0.15)
				)
				(justify mirror)
			)
		)
		(sheetname "FPGA supply")
		(sheetfile "fpga-supply.kicad_sch")
		(attr smd)
		(fp_rect
			(start -0.925 0.47)
			(end 0.925 -0.47)
			(stroke
				(width 0.05)
				(type default)
			)
			(fill no)
			(layer "B.CrtYd")
		)
		(fp_line
			(start 0.504 -0.248)
			(end -0.494 -0.248)
			(stroke
				(width 0.15)
				(type solid)
			)
			(layer "B.Fab")
		)
		(fp_line
			(start -0.494 -0.248)
			(end -0.494 0.25)
			(stroke
				(width 0.15)
				(type solid)
			)
			(layer "B.Fab")
		)
		(fp_line
			(start 0.504 0.25)
			(end 0.504 -0.248)
			(stroke
				(width 0.15)
				(type solid)
			)
			(layer "B.Fab")
		)
		(fp_line
			(start -0.494 0.25)
			(end 0.504 0.25)
			(stroke
				(width 0.15)
				(type solid)
			)
			(layer "B.Fab")
		)
		(pad "1" smd roundrect
			(at -0.48 0 90)
			(size 0.59 0.64)
			(layers "B.Cu" "B.Mask" "B.Paste")
			(roundrect_rratio 0.25)
			(net 1 "GND")
			(pintype "passive")
		)
		(pad "2" smd roundrect
			(at 0.48 0 90)
			(size 0.59 0.64)
			(layers "B.Cu" "B.Mask" "B.Paste")
			(roundrect_rratio 0.25)
			(net 650 "+1V0")
			(pintype "passive")
		)
	)
)
